#ISCELL
  mstr_misc dns *
  *
#ISCELL
  pure_quanta quanta_title_block_c *
  *
#ISCELL
  pure_quanta_power cad_note *
  *
#ISCELL
  pure_quanta_power gnd *
  page158_i105
#ISCELL
  pure_quanta_power gnd *
  page158_i106
#ISCELL
  pure_quanta_power gnd *
  page158_i107
#ISCELL
  standard offpage *
  page158_i11
#ISCELL
  pure_quanta_power gnd *
  page158_i110
#ISCELL
  pure_quanta_power gnd *
  page158_i113
#ISCELL
  pure_quanta_power gnd *
  page158_i114
#ISCELL
  pure_quanta_power gnd *
  page158_i117
#ISCELL
  pure_quanta_power gnd *
  page158_i118
#ISCELL
  standard offpage *
  page158_i12
#CELL
  pure_quanta q_res *
  page158_i120
#CELL
  pure_quanta q_res *
  page158_i121
#CELL
  pure_quanta q_res *
  page158_i124
#CELL
  pure_quanta q_res *
  page158_i125
#CELL
  pure_quanta q_res *
  page158_i126
#CELL
  pure_quanta q_res *
  page158_i127
#ISCELL
  standard offpage *
  page158_i13
#CELL
  pure_quanta q_cap *
  page158_i137
#CELL
  pure_quanta q_cap *
  page158_i138
#CELL
  pure_quanta q_cap *
  page158_i139
#ISCELL
  standard offpage *
  page158_i14
#CELL
  pure_quanta q_cap *
  page158_i140
#CELL
  pure_quanta q_cap *
  page158_i141
#CELL
  pure_quanta q_cap *
  page158_i142
#CELL
  pure_quanta q_cap *
  page158_i143
#CELL
  pure_quanta q_cap *
  page158_i144
#CELL
  pure_quanta q_res *
  page158_i145
#CELL
  pure_quanta q_res *
  page158_i146
#CELL
  pure_quanta q_cap *
  page158_i147
#CELL
  pure_quanta q_cap *
  page158_i148
#ISCELL
  standard offpage *
  page158_i15
#ISCELL
  standard offpage *
  page158_i16
#CELL
  pure_quanta q_res *
  page158_i3
#ISCELL
  standard offpage *
  page158_i39
#CELL
  pure_quanta q_res *
  page158_i4
#ISCELL
  standard offpage *
  page158_i40
#ISCELL
  standard offpage *
  page158_i41
#ISCELL
  standard offpage *
  page158_i42
#ISCELL
  standard offpage *
  page158_i43
#ISCELL
  standard offpage *
  page158_i44
#ISCELL
  standard offpage *
  page158_i45
#ISCELL
  standard offpage *
  page158_i46
#ISCELL
  standard offpage *
  page158_i47
#ISCELL
  standard offpage *
  page158_i48
#CELL
  pure_quanta q_cap_diffbus *
  page158_i49
#CELL
  pure_quanta q_res *
  page158_i5
#CELL
  pure_quanta q_cap_diffbus *
  page158_i50
#ISCELL
  standard offpage *
  page158_i53
#ISCELL
  standard offpage *
  page158_i54
#CELL
  pure_quanta q_res *
  page158_i6
#ISCELL
  standard offpage *
  page158_i65
#ISCELL
  standard offpage *
  page158_i66
#ISCELL
  standard offpage *
  page158_i67
#ISCELL
  standard offpage *
  page158_i68
#ISCELL
  standard offpage *
  page158_i69
#ISCELL
  standard offpage *
  page158_i70
#CELL
  pure_quanta q_res *
  page158_i71
#CELL
  pure_quanta q_res *
  page158_i72
#CELL
  pure_quanta q_res *
  page158_i73
#CELL
  pure_quanta q_res *
  page158_i74
#ISCELL
  standard offpage *
  page158_i75
#ISCELL
  standard offpage *
  page158_i76
#ISCELL
  standard offpage *
  page158_i77
#ISCELL
  standard offpage *
  page158_i78
#ISCELL
  standard offpage *
  page158_i83
#ISCELL
  standard offpage *
  page158_i84
#CELL
  pure_quanta q_cap_diffbus *
  page158_i85
#CELL
  pure_quanta q_cap_diffbus *
  page158_i86
#CELL
  pure_quanta q_cap_diffbus *
  page158_i87
#CELL
  pure_quanta q_cap_diffbus *
  page158_i88
#ISCELL
  standard offpage *
  page158_i89
#ISCELL
  standard offpage *
  page158_i90
#ISCELL
  standard offpage *
  page158_i95
#ISCELL
  standard offpage *
  page158_i96
#ISCELL
  standard offpage *
  page158_i97
#ISCELL
  standard offpage *
  page158_i98
